(kicad_pcb
	(version 20260206)
	(generator "pcbnew")
	(generator_version "10.0")
	(general
		(thickness 1.6)
		(legacy_teardrops no)
	)
	(paper "A4")
	(title_block
		(title "Bryce Canyon_SCC_16316-1_OCP.brd")
		(comment 1 "Bryce Canyon / footprints 903-910 of 1561")
	)
	(layers
		(0 "F.Cu" signal "TOP")
		(4 "In1.Cu" signal "L2GND")
		(6 "In2.Cu" signal "L3")
		(8 "In3.Cu" signal "L4VCC")
		(10 "In4.Cu" signal "L5VCC")
		(12 "In5.Cu" signal "L6")
		(14 "In6.Cu" signal "L7GND")
		(2 "B.Cu" signal "BOTTOM")
		(9 "F.Adhes" user "F.Adhesive")
		(11 "B.Adhes" user "B.Adhesive")
		(13 "F.Paste" user "Package Geometry/Pastemask Top")
		(15 "B.Paste" user "Package Geometry/Pastemask Bottom")
		(5 "F.SilkS" user "Ref Des/Silkscreen Top")
		(7 "B.SilkS" user "Ref Des/Silkscreen Bottom")
		(1 "F.Mask" user "Board Geometry/Soldermask Top")
		(3 "B.Mask" user "Board Geometry/Soldermask Bottom")
		(17 "Dwgs.User" user "User.Drawings")
		(19 "Cmts.User" user "User.Comments")
		(21 "Eco1.User" user "User.Eco1")
		(23 "Eco2.User" user "User.Eco2")
		(25 "Edge.Cuts" user "Board Geometry/Outline")
		(27 "Margin" user)
		(31 "F.CrtYd" user "Package Geometry/Place Bound Top")
		(29 "B.CrtYd" user "Package Geometry/Place Bound Bottom")
		(35 "F.Fab" user "Ref Des/Assembly Top")
		(33 "B.Fab" user "Ref Des/Assembly Bottom")
	)
	(footprint ""
		(layer "B.Cu")
		(at 127.325374 -87.251794)
		(property "Reference" "R236"
			(at 0 0 0)
			(layer "B.SilkS")
			(hide yes)
			(effects
				(font
					(size 1.27 1.27)
				)
				(justify mirror)
			)
		)
		(property "Value" "4K75R2F-1-GP"
			(at -0.064008 -3.993896 0)
			(unlocked yes)
			(layer "B.Fab")
			(hide yes)
			(effects
				(font
					(size 1.016 1.016)
					(thickness 0.1524)
				)
				(justify mirror)
			)
		)
		(property "Device Type" "R402H16"
			(at -0.064008 -5.517896 0)
			(unlocked yes)
			(layer "B.Fab")
			(hide yes)
			(effects
				(font
					(size 1.016 1.016)
					(thickness 0.1524)
				)
				(justify mirror)
			)
		)
		(duplicate_pad_numbers_are_jumpers no)
		(fp_line
			(start -0.508 -0.9398)
			(end 0.508 -0.9398)
			(stroke
				(width 0.1524)
				(type default)
			)
			(layer "B.SilkS")
		)
		(fp_line
			(start 0.508 -0.9398)
			(end 0.508 0.9398)
			(stroke
				(width 0.1524)
				(type default)
			)
			(layer "B.SilkS")
		)
		(fp_rect
			(start 0.508 0.9398)
			(end -0.508 -0.9398)
			(stroke
				(width 0)
				(type default)
			)
			(fill no)
			(layer "B.CrtYd")
		)
		(fp_rect
			(start 0.508 0.9398)
			(end -0.508 -0.9398)
			(stroke
				(width 0)
				(type default)
			)
			(fill no)
			(layer "B.Fab")
		)
		(pad "1" smd custom
			(at 0 -0.4445 180)
			(size 0.1397 0.1397)
			(layers "B.Cu" "B.Mask" "B.Paste")
			(net "P1V8_E")
			(options
				(clearance outline)
				(anchor circle)
			)
			(primitives
				(gr_poly
					(pts
						(arc
							(start -0.1778 0.2794)
							(mid -0.249642 0.249642)
							(end -0.2794 0.1778)
						)
						(arc
							(start -0.2794 -0.1778)
							(mid -0.249642 -0.249642)
							(end -0.1778 -0.2794)
						)
						(arc
							(start 0.1778 -0.2794)
							(mid 0.249642 -0.249642)
							(end 0.2794 -0.1778)
						)
						(arc
							(start 0.2794 0.1778)
							(mid 0.249642 0.249642)
							(end 0.1778 0.2794)
						)
					)
					(width 0)
					(fill yes)
				)
			)
		)
		(pad "2" smd custom
			(at 0 0.4445 180)
			(size 0.1397 0.1397)
			(layers "B.Cu" "B.Mask" "B.Paste")
			(net "ICE_TRST_N")
			(options
				(clearance outline)
				(anchor circle)
			)
			(primitives
				(gr_poly
					(pts
						(arc
							(start -0.1778 0.2794)
							(mid -0.249642 0.249642)
							(end -0.2794 0.1778)
						)
						(arc
							(start -0.2794 -0.1778)
							(mid -0.249642 -0.249642)
							(end -0.1778 -0.2794)
						)
						(arc
							(start 0.1778 -0.2794)
							(mid 0.249642 -0.249642)
							(end 0.2794 -0.1778)
						)
						(arc
							(start 0.2794 0.1778)
							(mid 0.249642 0.249642)
							(end 0.1778 0.2794)
						)
					)
					(width 0)
					(fill yes)
				)
			)
		)
	)
	(footprint ""
		(layer "B.Cu")
		(at 100.33 -57.4802 -90)
		(property "Reference" "C195"
			(at 0 0 90)
			(layer "B.SilkS")
			(hide yes)
			(effects
				(font
					(size 1.27 1.27)
				)
				(justify mirror)
			)
		)
		(property "Value" "SCD1U6D3V1KX-GP"
			(at 2.8321 -1.7399 270)
			(unlocked yes)
			(layer "B.Fab")
			(hide yes)
			(effects
				(font
					(size 1.016 1.016)
					(thickness 0.1524)
				)
				(justify mirror)
			)
		)
		(property "Device Type" "C0201H13"
			(at 2.8321 -3.2639 270)
			(unlocked yes)
			(layer "B.Fab")
			(hide yes)
			(effects
				(font
					(size 1.016 1.016)
					(thickness 0.1524)
				)
				(justify mirror)
			)
		)
		(duplicate_pad_numbers_are_jumpers no)
		(fp_rect
			(start 0.2794 0.6477)
			(end -0.2794 -0.6477)
			(stroke
				(width 0)
				(type default)
			)
			(fill no)
			(layer "B.CrtYd")
		)
		(fp_rect
			(start 0.2794 0.6477)
			(end -0.2794 -0.6477)
			(stroke
				(width 0)
				(type default)
			)
			(fill no)
			(layer "B.Fab")
		)
		(pad "1" smd custom
			(at 0 -0.2794 90)
			(size 0.0762 0.0762)
			(layers "B.Cu" "B.Mask" "B.Paste")
			(net "XTAL_VDDA18")
			(options
				(clearance outline)
				(anchor circle)
			)
			(primitives
				(gr_poly
					(pts
						(arc
							(start 0.1524 0.127)
							(mid 0.137521 0.162921)
							(end 0.1016 0.1778)
						)
						(arc
							(start -0.1016 0.1778)
							(mid -0.137521 0.162921)
							(end -0.1524 0.127)
						)
						(arc
							(start -0.1524 -0.127)
							(mid -0.137521 -0.162921)
							(end -0.1016 -0.1778)
						)
						(arc
							(start 0.1016 -0.1778)
							(mid 0.137521 -0.162921)
							(end 0.1524 -0.127)
						)
					)
					(width 0)
					(fill yes)
				)
			)
		)
		(pad "2" smd custom
			(at 0 0.2794 90)
			(size 0.0762 0.0762)
			(layers "B.Cu" "B.Mask" "B.Paste")
			(net "GND")
			(options
				(clearance outline)
				(anchor circle)
			)
			(primitives
				(gr_poly
					(pts
						(arc
							(start 0.1524 0.127)
							(mid 0.137521 0.162921)
							(end 0.1016 0.1778)
						)
						(arc
							(start -0.1016 0.1778)
							(mid -0.137521 0.162921)
							(end -0.1524 0.127)
						)
						(arc
							(start -0.1524 -0.127)
							(mid -0.137521 -0.162921)
							(end -0.1016 -0.1778)
						)
						(arc
							(start 0.1016 -0.1778)
							(mid 0.137521 -0.162921)
							(end 0.1524 -0.127)
						)
					)
					(width 0)
					(fill yes)
				)
			)
		)
	)
	(footprint ""
		(layer "B.Cu")
		(at 137.603738 -84.70011)
		(property "Reference" "R51"
			(at 0 0 0)
			(layer "B.SilkS")
			(hide yes)
			(effects
				(font
					(size 1.27 1.27)
				)
				(justify mirror)
			)
		)
		(property "Value" "4K7R2F-GP"
			(at -0.064008 -3.993896 0)
			(unlocked yes)
			(layer "B.Fab")
			(hide yes)
			(effects
				(font
					(size 1.016 1.016)
					(thickness 0.1524)
				)
				(justify mirror)
			)
		)
		(property "Device Type" "R402H16"
			(at -0.064008 -5.517896 0)
			(unlocked yes)
			(layer "B.Fab")
			(hide yes)
			(effects
				(font
					(size 1.016 1.016)
					(thickness 0.1524)
				)
				(justify mirror)
			)
		)
		(duplicate_pad_numbers_are_jumpers no)
		(fp_line
			(start -0.508 -0.9398)
			(end 0.508 -0.9398)
			(stroke
				(width 0.1524)
				(type default)
			)
			(layer "B.SilkS")
		)
		(fp_line
			(start 0.508 -0.9398)
			(end 0.508 0.9398)
			(stroke
				(width 0.1524)
				(type default)
			)
			(layer "B.SilkS")
		)
		(fp_rect
			(start 0.508 0.9398)
			(end -0.508 -0.9398)
			(stroke
				(width 0)
				(type default)
			)
			(fill no)
			(layer "B.CrtYd")
		)
		(fp_rect
			(start 0.508 0.9398)
			(end -0.508 -0.9398)
			(stroke
				(width 0)
				(type default)
			)
			(fill no)
			(layer "B.Fab")
		)
		(pad "1" smd custom
			(at 0 -0.4445 180)
			(size 0.1397 0.1397)
			(layers "B.Cu" "B.Mask" "B.Paste")
			(net "P1V8_E")
			(options
				(clearance outline)
				(anchor circle)
			)
			(primitives
				(gr_poly
					(pts
						(arc
							(start -0.1778 0.2794)
							(mid -0.249642 0.249642)
							(end -0.2794 0.1778)
						)
						(arc
							(start -0.2794 -0.1778)
							(mid -0.249642 -0.249642)
							(end -0.1778 -0.2794)
						)
						(arc
							(start 0.1778 -0.2794)
							(mid 0.249642 -0.249642)
							(end 0.2794 -0.1778)
						)
						(arc
							(start 0.2794 0.1778)
							(mid 0.249642 0.249642)
							(end 0.1778 0.2794)
						)
					)
					(width 0)
					(fill yes)
				)
			)
		)
		(pad "2" smd custom
			(at 0 0.4445 180)
			(size 0.1397 0.1397)
			(layers "B.Cu" "B.Mask" "B.Paste")
			(net "I2C_BMC_RMT_SDA1_LS")
			(options
				(clearance outline)
				(anchor circle)
			)
			(primitives
				(gr_poly
					(pts
						(arc
							(start -0.1778 0.2794)
							(mid -0.249642 0.249642)
							(end -0.2794 0.1778)
						)
						(arc
							(start -0.2794 -0.1778)
							(mid -0.249642 -0.249642)
							(end -0.1778 -0.2794)
						)
						(arc
							(start 0.1778 -0.2794)
							(mid 0.249642 -0.249642)
							(end 0.2794 -0.1778)
						)
						(arc
							(start 0.2794 0.1778)
							(mid 0.249642 0.249642)
							(end 0.1778 0.2794)
						)
					)
					(width 0)
					(fill yes)
				)
			)
		)
	)
	(footprint ""
		(layer "B.Cu")
		(at 108.2802 -62.865 180)
		(property "Reference" "C221"
			(at 0 0 0)
			(layer "B.SilkS")
			(hide yes)
			(effects
				(font
					(size 1.27 1.27)
				)
				(justify mirror)
			)
		)
		(property "Value" "SCD1U16V2KX-3GP"
			(at -1.1811 -2.7051 180)
			(unlocked yes)
			(layer "B.Fab")
			(hide yes)
			(effects
				(font
					(size 1.016 1.016)
					(thickness 0.1524)
				)
				(justify mirror)
			)
		)
		(property "Device Type" "C402H22"
			(at -1.1811 -4.2291 180)
			(unlocked yes)
			(layer "B.Fab")
			(hide yes)
			(effects
				(font
					(size 1.016 1.016)
					(thickness 0.1524)
				)
				(justify mirror)
			)
		)
		(duplicate_pad_numbers_are_jumpers no)
		(fp_rect
			(start 0.4318 0.9525)
			(end -0.4318 -0.9525)
			(stroke
				(width 0)
				(type default)
			)
			(fill no)
			(layer "B.CrtYd")
		)
		(fp_rect
			(start 0.4318 0.9525)
			(end -0.4318 -0.9525)
			(stroke
				(width 0)
				(type default)
			)
			(fill no)
			(layer "B.Fab")
		)
		(pad "1" smd custom
			(at 0 -0.4445)
			(size 0.1524 0.1524)
			(layers "B.Cu" "B.Mask" "B.Paste")
			(net "GB_VDDH")
			(options
				(clearance outline)
				(anchor circle)
			)
			(primitives
				(gr_poly
					(pts
						(arc
							(start 0.3048 0.2032)
							(mid 0.275042 0.275042)
							(end 0.2032 0.3048)
						)
						(arc
							(start -0.2032 0.3048)
							(mid -0.275042 0.275042)
							(end -0.3048 0.2032)
						)
						(arc
							(start -0.3048 -0.2032)
							(mid -0.275042 -0.275042)
							(end -0.2032 -0.3048)
						)
						(arc
							(start 0.2032 -0.3048)
							(mid 0.275042 -0.275042)
							(end 0.3048 -0.2032)
						)
					)
					(width 0)
					(fill yes)
				)
			)
		)
		(pad "2" smd custom
			(at 0 0.4445)
			(size 0.1524 0.1524)
			(layers "B.Cu" "B.Mask" "B.Paste")
			(net "GND")
			(options
				(clearance outline)
				(anchor circle)
			)
			(primitives
				(gr_poly
					(pts
						(arc
							(start 0.3048 0.2032)
							(mid 0.275042 0.275042)
							(end 0.2032 0.3048)
						)
						(arc
							(start -0.2032 0.3048)
							(mid -0.275042 0.275042)
							(end -0.3048 0.2032)
						)
						(arc
							(start -0.3048 -0.2032)
							(mid -0.275042 -0.275042)
							(end -0.2032 -0.3048)
						)
						(arc
							(start 0.2032 -0.3048)
							(mid 0.275042 -0.275042)
							(end 0.3048 -0.2032)
						)
					)
					(width 0)
					(fill yes)
				)
			)
		)
	)
	(footprint ""
		(layer "B.Cu")
		(at 189.397386 -46.682152 -90)
		(property "Reference" "TP108"
			(at 0 0 90)
			(layer "B.SilkS")
			(hide yes)
			(effects
				(font
					(size 1.27 1.27)
				)
				(justify mirror)
			)
		)
		(property "Value" "TPAD28-2-GP"
			(at 0.0127 -1.6637 270)
			(unlocked yes)
			(layer "B.Fab")
			(hide yes)
			(effects
				(font
					(size 1.016 1.016)
					(thickness 0.1524)
				)
				(justify mirror)
			)
		)
		(property "Device Type" "TPAD28"
			(at 0.0127 -3.1877 270)
			(unlocked yes)
			(layer "B.Fab")
			(hide yes)
			(effects
				(font
					(size 1.016 1.016)
					(thickness 0.1524)
				)
				(justify mirror)
			)
		)
		(duplicate_pad_numbers_are_jumpers no)
		(fp_poly
			(pts
				(arc
					(start 0 -0.3556)
					(mid 0 0.3556)
					(end 0 -0.3556)
				)
			)
			(stroke
				(width 0)
				(type default)
			)
			(fill no)
			(layer "B.CrtYd")
		)
		(fp_poly
			(pts
				(arc
					(start 0 -0.6096)
					(mid 0 0.6096)
					(end 0 -0.6096)
				)
			)
			(stroke
				(width 0)
				(type default)
			)
			(fill no)
			(layer "B.Fab")
		)
		(pad "1" smd circle
			(at 0 0 90)
			(size 0.7112 0.7112)
			(layers "B.Cu" "B.Mask" "B.Paste")
			(net "XM_ADDR_21")
		)
	)
	(footprint ""
		(layer "B.Cu")
		(at 176.22139 -39.709344 90)
		(property "Reference" "C412"
			(at 0 0 90)
			(layer "B.SilkS")
			(hide yes)
			(effects
				(font
					(size 1.27 1.27)
				)
				(justify mirror)
			)
		)
		(property "Value" "SC1U6D3V1MX-GP"
			(at -1.9177 2.0193 90)
			(unlocked yes)
			(layer "B.Fab")
			(hide yes)
			(effects
				(font
					(size 1.016 1.016)
					(thickness 0.1524)
				)
				(justify mirror)
			)
		)
		(property "Device Type" "C0201H14"
			(at -1.9177 0.4953 90)
			(unlocked yes)
			(layer "B.Fab")
			(hide yes)
			(effects
				(font
					(size 1.016 1.016)
					(thickness 0.1524)
				)
				(justify mirror)
			)
		)
		(duplicate_pad_numbers_are_jumpers no)
		(fp_rect
			(start 0.1524 0.3048)
			(end -0.1524 -0.3048)
			(stroke
				(width 0)
				(type default)
			)
			(fill no)
			(layer "B.CrtYd")
		)
		(fp_poly
			(pts
				(xy 0.2794 0.6477) (xy 0.2794 -0.6477) (xy -0.2794 -0.6477) (xy -0.2794 -0.1905) (xy -0.1524 -0.1905)
				(xy -0.1524 -0.3048) (xy 0.1524 -0.3048) (xy 0.1524 0.3048) (xy -0.1524 0.3048) (xy -0.1524 -0.1778)
				(xy -0.2794 -0.1778) (xy -0.2794 0.6477)
			)
			(stroke
				(width 0)
				(type default)
			)
			(fill no)
			(layer "B.CrtYd")
		)
		(fp_rect
			(start 0.2794 0.6477)
			(end -0.2794 -0.6477)
			(stroke
				(width 0)
				(type default)
			)
			(fill no)
			(layer "B.Fab")
		)
		(pad "1" smd custom
			(at 0 -0.2794 270)
			(size 0.0762 0.0762)
			(layers "B.Cu" "B.Mask" "B.Paste")
			(net "P0V975")
			(options
				(clearance outline)
				(anchor circle)
			)
			(primitives
				(gr_poly
					(pts
						(arc
							(start 0.1524 0.127)
							(mid 0.137521 0.162921)
							(end 0.1016 0.1778)
						)
						(arc
							(start -0.1016 0.1778)
							(mid -0.137521 0.162921)
							(end -0.1524 0.127)
						)
						(arc
							(start -0.1524 -0.127)
							(mid -0.137521 -0.162921)
							(end -0.1016 -0.1778)
						)
						(arc
							(start 0.1016 -0.1778)
							(mid 0.137521 -0.162921)
							(end 0.1524 -0.127)
						)
					)
					(width 0)
					(fill yes)
				)
			)
		)
		(pad "2" smd custom
			(at 0 0.2794 270)
			(size 0.0762 0.0762)
			(layers "B.Cu" "B.Mask" "B.Paste")
			(net "GND")
			(options
				(clearance outline)
				(anchor circle)
			)
			(primitives
				(gr_poly
					(pts
						(arc
							(start 0.1524 0.127)
							(mid 0.137521 0.162921)
							(end 0.1016 0.1778)
						)
						(arc
							(start -0.1016 0.1778)
							(mid -0.137521 0.162921)
							(end -0.1524 0.127)
						)
						(arc
							(start -0.1524 -0.127)
							(mid -0.137521 -0.162921)
							(end -0.1016 -0.1778)
						)
						(arc
							(start 0.1016 -0.1778)
							(mid 0.137521 -0.162921)
							(end 0.1524 -0.127)
						)
					)
					(width 0)
					(fill yes)
				)
			)
		)
	)
	(footprint ""
		(layer "B.Cu")
		(at 172.844206 -66.764916 -90)
		(property "Reference" "R547"
			(at 0 0 90)
			(layer "B.SilkS")
			(hide yes)
			(effects
				(font
					(size 1.27 1.27)
				)
				(justify mirror)
			)
		)
		(property "Value" "4K7R2F-GP"
			(at -0.064008 -3.993896 270)
			(unlocked yes)
			(layer "B.Fab")
			(hide yes)
			(effects
				(font
					(size 1.016 1.016)
					(thickness 0.1524)
				)
				(justify mirror)
			)
		)
		(property "Device Type" "R402H16"
			(at -0.064008 -5.517896 270)
			(unlocked yes)
			(layer "B.Fab")
			(hide yes)
			(effects
				(font
					(size 1.016 1.016)
					(thickness 0.1524)
				)
				(justify mirror)
			)
		)
		(duplicate_pad_numbers_are_jumpers no)
		(fp_line
			(start -0.508 -0.9398)
			(end 0.508 -0.9398)
			(stroke
				(width 0.1524)
				(type default)
			)
			(layer "B.SilkS")
		)
		(fp_line
			(start 0.508 -0.9398)
			(end 0.508 0.9398)
			(stroke
				(width 0.1524)
				(type default)
			)
			(layer "B.SilkS")
		)
		(fp_rect
			(start 0.508 0.9398)
			(end -0.508 -0.9398)
			(stroke
				(width 0)
				(type default)
			)
			(fill no)
			(layer "B.CrtYd")
		)
		(fp_rect
			(start 0.508 0.9398)
			(end -0.508 -0.9398)
			(stroke
				(width 0)
				(type default)
			)
			(fill no)
			(layer "B.Fab")
		)
		(pad "1" smd custom
			(at 0 -0.4445 90)
			(size 0.1397 0.1397)
			(layers "B.Cu" "B.Mask" "B.Paste")
			(net "IOC_VREF_SET_LS")
			(options
				(clearance outline)
				(anchor circle)
			)
			(primitives
				(gr_poly
					(pts
						(arc
							(start -0.1778 0.2794)
							(mid -0.249642 0.249642)
							(end -0.2794 0.1778)
						)
						(arc
							(start -0.2794 -0.1778)
							(mid -0.249642 -0.249642)
							(end -0.1778 -0.2794)
						)
						(arc
							(start 0.1778 -0.2794)
							(mid 0.249642 -0.249642)
							(end 0.2794 -0.1778)
						)
						(arc
							(start 0.2794 0.1778)
							(mid 0.249642 0.249642)
							(end 0.1778 0.2794)
						)
					)
					(width 0)
					(fill yes)
				)
			)
		)
		(pad "2" smd custom
			(at 0 0.4445 90)
			(size 0.1397 0.1397)
			(layers "B.Cu" "B.Mask" "B.Paste")
			(net "GND")
			(options
				(clearance outline)
				(anchor circle)
			)
			(primitives
				(gr_poly
					(pts
						(arc
							(start -0.1778 0.2794)
							(mid -0.249642 0.249642)
							(end -0.2794 0.1778)
						)
						(arc
							(start -0.2794 -0.1778)
							(mid -0.249642 -0.249642)
							(end -0.1778 -0.2794)
						)
						(arc
							(start 0.1778 -0.2794)
							(mid 0.249642 -0.249642)
							(end 0.2794 -0.1778)
						)
						(arc
							(start 0.2794 0.1778)
							(mid 0.249642 0.249642)
							(end 0.1778 0.2794)
						)
					)
					(width 0)
					(fill yes)
				)
			)
		)
	)
	(footprint ""
		(layer "B.Cu")
		(at 164.961316 -35.202114 -90)
		(property "Reference" "C397"
			(at 0 0 90)
			(layer "B.SilkS")
			(hide yes)
			(effects
				(font
					(size 1.27 1.27)
				)
				(justify mirror)
			)
		)
		(property "Value" "SCD1U16V2KX-3GP"
			(at -1.1811 -2.7051 270)
			(unlocked yes)
			(layer "B.Fab")
			(hide yes)
			(effects
				(font
					(size 1.016 1.016)
					(thickness 0.1524)
				)
				(justify mirror)
			)
		)
		(property "Device Type" "C402H22"
			(at -1.1811 -4.2291 270)
			(unlocked yes)
			(layer "B.Fab")
			(hide yes)
			(effects
				(font
					(size 1.016 1.016)
					(thickness 0.1524)
				)
				(justify mirror)
			)
		)
		(duplicate_pad_numbers_are_jumpers no)
		(fp_rect
			(start 0.4318 0.9525)
			(end -0.4318 -0.9525)
			(stroke
				(width 0)
				(type default)
			)
			(fill no)
			(layer "B.CrtYd")
		)
		(fp_rect
			(start 0.4318 0.9525)
			(end -0.4318 -0.9525)
			(stroke
				(width 0)
				(type default)
			)
			(fill no)
			(layer "B.Fab")
		)
		(pad "1" smd custom
			(at 0 -0.4445 90)
			(size 0.1524 0.1524)
			(layers "B.Cu" "B.Mask" "B.Paste")
			(net "SAS0_AVDD")
			(options
				(clearance outline)
				(anchor circle)
			)
			(primitives
				(gr_poly
					(pts
						(arc
							(start 0.3048 0.2032)
							(mid 0.275042 0.275042)
							(end 0.2032 0.3048)
						)
						(arc
							(start -0.2032 0.3048)
							(mid -0.275042 0.275042)
							(end -0.3048 0.2032)
						)
						(arc
							(start -0.3048 -0.2032)
							(mid -0.275042 -0.275042)
							(end -0.2032 -0.3048)
						)
						(arc
							(start 0.2032 -0.3048)
							(mid 0.275042 -0.275042)
							(end 0.3048 -0.2032)
						)
					)
					(width 0)
					(fill yes)
				)
			)
		)
		(pad "2" smd custom
			(at 0 0.4445 90)
			(size 0.1524 0.1524)
			(layers "B.Cu" "B.Mask" "B.Paste")
			(net "GND")
			(options
				(clearance outline)
				(anchor circle)
			)
			(primitives
				(gr_poly
					(pts
						(arc
							(start 0.3048 0.2032)
							(mid 0.275042 0.275042)
							(end 0.2032 0.3048)
						)
						(arc
							(start -0.2032 0.3048)
							(mid -0.275042 0.275042)
							(end -0.3048 0.2032)
						)
						(arc
							(start -0.3048 -0.2032)
							(mid -0.275042 -0.275042)
							(end -0.2032 -0.3048)
						)
						(arc
							(start 0.2032 -0.3048)
							(mid 0.275042 -0.275042)
							(end 0.3048 -0.2032)
						)
					)
					(width 0)
					(fill yes)
				)
			)
		)
	)
)
